FILE_TYPE = CONNECTIVITY;
{Allegro Design Entry HDL 17.2-2016 S081 (4005846) 1/11/2022}
"PAGE_NUMBER" = 250;
0"NC";
END.
